(kicad_pcb
	(version 20260206)
	(generator "pcbnew")
	(generator_version "10.0")
	(general
		(thickness 1.6)
		(legacy_teardrops no)
	)
	(paper "A4")
	(title_block
		(title "01162023_DA0F0TEBIF0_F0T_Expander_BD_F_brd_V02_OCP.brd")
		(comment 1 "Grand Teton / footprint 1670 of 9728 (J24), pads 1-109 of 179")
	)
	(layers
		(0 "F.Cu" signal "TOP")
		(4 "In1.Cu" signal "GND")
		(6 "In2.Cu" signal "VCC")
		(8 "In3.Cu" signal "VCC1")
		(10 "In4.Cu" signal "GND1")
		(12 "In5.Cu" signal "IN1")
		(14 "In6.Cu" signal "GND2")
		(16 "In7.Cu" signal "IN2")
		(18 "In8.Cu" signal "GND3")
		(20 "In9.Cu" signal "IN3")
		(22 "In10.Cu" signal "GND4")
		(24 "In11.Cu" signal "IN4")
		(26 "In12.Cu" signal "GND5")
		(28 "In13.Cu" signal "IN5")
		(30 "In14.Cu" signal "GND6")
		(32 "In15.Cu" signal "IN6")
		(34 "In16.Cu" signal "GND7")
		(2 "B.Cu" signal "BOTTOM")
		(9 "F.Adhes" user "F.Adhesive")
		(11 "B.Adhes" user "B.Adhesive")
		(13 "F.Paste" user "Package Geometry/Pastemask Top")
		(15 "B.Paste" user "Package Geometry/Pastemask Bottom")
		(5 "F.SilkS" user "Ref Des/Silkscreen Top")
		(7 "B.SilkS" user "Ref Des/Silkscreen Bottom")
		(1 "F.Mask" user "Board Geometry/Soldermask Top")
		(3 "B.Mask" user "Board Geometry/Soldermask Bottom")
		(17 "Dwgs.User" user "User.Drawings")
		(19 "Cmts.User" user "User.Comments")
		(21 "Eco1.User" user "User.Eco1")
		(23 "Eco2.User" user "User.Eco2")
		(25 "Edge.Cuts" user "Board Geometry/Outline")
		(27 "Margin" user)
		(31 "F.CrtYd" user "Package Geometry/Place Bound Top")
		(29 "B.CrtYd" user "Package Geometry/Place Bound Bottom")
		(35 "F.Fab" user "Ref Des/Assembly Top")
		(33 "B.Fab" user "Ref Des/Assembly Bottom")
	)
	(footprint ""
		(layer "F.Cu")
		(at 279.519888 -127.700024)
		(property "Reference" "J24"
			(at -5.198618 34.837624 90)
			(unlocked yes)
			(layer "F.SilkS")
			(effects
				(font
					(size 0.7874 0.5842)
					(thickness 0.1524)
				)
				(justify left)
			)
		)
		(property "Value" ""
			(at 0 0 0)
			(layer "F.Fab")
			(effects
				(font
					(size 1.27 1.27)
				)
			)
		)
		(duplicate_pad_numbers_are_jumpers no)
		(pad "" np_thru_hole circle
			(at -0.727456 -32.485076)
			(size 1.1176 1.1176)
			(drill 1.1176)
			(layers "*.Cu" "*.Mask")
			(clearance 0.381)
			(thermal_gap 0.381)
		)
		(pad "" np_thru_hole circle
			(at 1.022604 32.485076)
			(size 1.1176 1.1176)
			(drill 1.1176)
			(layers "*.Cu" "*.Mask")
			(clearance 0.381)
			(thermal_gap 0.381)
		)
		(pad "A1" smd rect
			(at 3.322574 -18.465038 270)
			(size 0.3556 1.2192)
			(layers "F.Cu" "F.Mask" "F.Paste")
			(net "GND")
		)
		(pad "A2" smd rect
			(at 3.322574 -17.86509 270)
			(size 0.3556 1.2192)
			(layers "F.Cu" "F.Mask" "F.Paste")
			(net "GND")
		)
		(pad "A3" smd rect
			(at 3.322574 -17.264888 270)
			(size 0.3556 1.2192)
			(layers "F.Cu" "F.Mask" "F.Paste")
			(net "GND")
		)
		(pad "A4" smd rect
			(at 3.322574 -16.66494 270)
			(size 0.3556 1.2192)
			(layers "F.Cu" "F.Mask" "F.Paste")
			(net "GND")
		)
		(pad "A5" smd rect
			(at 3.322574 -16.064992 270)
			(size 0.3556 1.2192)
			(layers "F.Cu" "F.Mask" "F.Paste")
			(net "GND")
		)
		(pad "A6" smd rect
			(at 3.322574 -15.465044 270)
			(size 0.3556 1.2192)
			(layers "F.Cu" "F.Mask" "F.Paste")
			(net "GND")
		)
		(pad "A7" smd rect
			(at 3.322574 -14.865096 270)
			(size 0.3556 1.2192)
			(layers "F.Cu" "F.Mask" "F.Paste")
			(net "SMB_NIC4_LS_SCL")
		)
		(pad "A8" smd rect
			(at 3.322574 -14.264894 270)
			(size 0.3556 1.2192)
			(layers "F.Cu" "F.Mask" "F.Paste")
			(net "SMB_NIC4_LS_SDA")
		)
		(pad "A9" smd rect
			(at 3.322574 -13.664946 270)
			(size 0.3556 1.2192)
			(layers "F.Cu" "F.Mask" "F.Paste")
			(net "RST_SMB_NIC4_MUX_ISO_R_N")
		)
		(pad "A10" smd rect
			(at 3.322574 -13.064998 270)
			(size 0.3556 1.2192)
			(layers "F.Cu" "F.Mask" "F.Paste")
			(net "GND")
		)
		(pad "A11" smd rect
			(at 3.322574 -12.46505 270)
			(size 0.3556 1.2192)
			(layers "F.Cu" "F.Mask" "F.Paste")
			(net "RST_NIC4_PERST1_R_N")
		)
		(pad "A12" smd rect
			(at 3.322574 -11.865102 270)
			(size 0.3556 1.2192)
			(layers "F.Cu" "F.Mask" "F.Paste")
			(net "PRSNTB2_NIC4_N")
		)
		(pad "A13" smd rect
			(at 3.322574 -11.2649 270)
			(size 0.3556 1.2192)
			(layers "F.Cu" "F.Mask" "F.Paste")
			(net "GND")
		)
		(pad "A14" smd rect
			(at 3.322574 -10.664952 270)
			(size 0.3556 1.2192)
			(layers "F.Cu" "F.Mask" "F.Paste")
			(net "Net_2627")
		)
		(pad "A15" smd rect
			(at 3.322574 -10.065004 270)
			(size 0.3556 1.2192)
			(layers "F.Cu" "F.Mask" "F.Paste")
			(net "Net_2630")
		)
		(pad "A16" smd rect
			(at 3.322574 -9.465056 270)
			(size 0.3556 1.2192)
			(layers "F.Cu" "F.Mask" "F.Paste")
			(net "GND")
		)
		(pad "A17" smd rect
			(at 3.322574 -8.865108 270)
			(size 0.3556 1.2192)
			(layers "F.Cu" "F.Mask" "F.Paste")
			(net "P5E_PEX2_STN1_RX_DN<31>")
		)
		(pad "A18" smd rect
			(at 3.322574 -8.264906 270)
			(size 0.3556 1.2192)
			(layers "F.Cu" "F.Mask" "F.Paste")
			(net "P5E_PEX2_STN1_RX_DP<31>")
		)
		(pad "A19" smd rect
			(at 3.322574 -7.664958 270)
			(size 0.3556 1.2192)
			(layers "F.Cu" "F.Mask" "F.Paste")
			(net "GND")
		)
		(pad "A20" smd rect
			(at 3.322574 -7.06501 270)
			(size 0.3556 1.2192)
			(layers "F.Cu" "F.Mask" "F.Paste")
			(net "P5E_PEX2_STN1_RX_DN<30>")
		)
		(pad "A21" smd rect
			(at 3.322574 -6.465062 270)
			(size 0.3556 1.2192)
			(layers "F.Cu" "F.Mask" "F.Paste")
			(net "P5E_PEX2_STN1_RX_DP<30>")
		)
		(pad "A22" smd rect
			(at 3.322574 -5.865114 270)
			(size 0.3556 1.2192)
			(layers "F.Cu" "F.Mask" "F.Paste")
			(net "GND")
		)
		(pad "A23" smd rect
			(at 3.322574 -5.264912 270)
			(size 0.3556 1.2192)
			(layers "F.Cu" "F.Mask" "F.Paste")
			(net "P5E_PEX2_STN1_RX_DN<29>")
		)
		(pad "A24" smd rect
			(at 3.322574 -4.664964 270)
			(size 0.3556 1.2192)
			(layers "F.Cu" "F.Mask" "F.Paste")
			(net "P5E_PEX2_STN1_RX_DP<29>")
		)
		(pad "A25" smd rect
			(at 3.322574 -4.065016 270)
			(size 0.3556 1.2192)
			(layers "F.Cu" "F.Mask" "F.Paste")
			(net "GND")
		)
		(pad "A26" smd rect
			(at 3.322574 -3.465068 270)
			(size 0.3556 1.2192)
			(layers "F.Cu" "F.Mask" "F.Paste")
			(net "P5E_PEX2_STN1_RX_DN<28>")
		)
		(pad "A27" smd rect
			(at 3.322574 -2.86512 270)
			(size 0.3556 1.2192)
			(layers "F.Cu" "F.Mask" "F.Paste")
			(net "P5E_PEX2_STN1_RX_DP<28>")
		)
		(pad "A28" smd rect
			(at 3.322574 -2.264918 270)
			(size 0.3556 1.2192)
			(layers "F.Cu" "F.Mask" "F.Paste")
			(net "GND")
		)
		(pad "A29" smd rect
			(at 3.322574 1.74498 270)
			(size 0.3556 1.2192)
			(layers "F.Cu" "F.Mask" "F.Paste")
			(net "GND")
		)
		(pad "A30" smd rect
			(at 3.322574 2.344928 270)
			(size 0.3556 1.2192)
			(layers "F.Cu" "F.Mask" "F.Paste")
			(net "P5E_PEX2_STN1_RX_DN<27>")
		)
		(pad "A31" smd rect
			(at 3.322574 2.944876 270)
			(size 0.3556 1.2192)
			(layers "F.Cu" "F.Mask" "F.Paste")
			(net "P5E_PEX2_STN1_RX_DP<27>")
		)
		(pad "A32" smd rect
			(at 3.322574 3.545078 270)
			(size 0.3556 1.2192)
			(layers "F.Cu" "F.Mask" "F.Paste")
			(net "GND")
		)
		(pad "A33" smd rect
			(at 3.322574 4.145026 270)
			(size 0.3556 1.2192)
			(layers "F.Cu" "F.Mask" "F.Paste")
			(net "P5E_PEX2_STN1_RX_DN<26>")
		)
		(pad "A34" smd rect
			(at 3.322574 4.744974 270)
			(size 0.3556 1.2192)
			(layers "F.Cu" "F.Mask" "F.Paste")
			(net "P5E_PEX2_STN1_RX_DP<26>")
		)
		(pad "A35" smd rect
			(at 3.322574 5.344922 270)
			(size 0.3556 1.2192)
			(layers "F.Cu" "F.Mask" "F.Paste")
			(net "GND")
		)
		(pad "A36" smd rect
			(at 3.322574 5.945124 270)
			(size 0.3556 1.2192)
			(layers "F.Cu" "F.Mask" "F.Paste")
			(net "P5E_PEX2_STN1_RX_DN<25>")
		)
		(pad "A37" smd rect
			(at 3.322574 6.545072 270)
			(size 0.3556 1.2192)
			(layers "F.Cu" "F.Mask" "F.Paste")
			(net "P5E_PEX2_STN1_RX_DP<25>")
		)
		(pad "A38" smd rect
			(at 3.322574 7.14502 270)
			(size 0.3556 1.2192)
			(layers "F.Cu" "F.Mask" "F.Paste")
			(net "GND")
		)
		(pad "A39" smd rect
			(at 3.322574 7.744968 270)
			(size 0.3556 1.2192)
			(layers "F.Cu" "F.Mask" "F.Paste")
			(net "P5E_PEX2_STN1_RX_DN<24>")
		)
		(pad "A40" smd rect
			(at 3.322574 8.344916 270)
			(size 0.3556 1.2192)
			(layers "F.Cu" "F.Mask" "F.Paste")
			(net "P5E_PEX2_STN1_RX_DP<24>")
		)
		(pad "A41" smd rect
			(at 3.322574 8.945118 270)
			(size 0.3556 1.2192)
			(layers "F.Cu" "F.Mask" "F.Paste")
			(net "GND")
		)
		(pad "A42" smd rect
			(at 3.322574 9.545066 270)
			(size 0.3556 1.2192)
			(layers "F.Cu" "F.Mask" "F.Paste")
			(net "PRSNTB1_NIC4_N")
		)
		(pad "A43" smd rect
			(at 3.322574 14.454886 270)
			(size 0.3556 1.2192)
			(layers "F.Cu" "F.Mask" "F.Paste")
			(net "GND")
		)
		(pad "A44" smd rect
			(at 3.322574 15.055088 270)
			(size 0.3556 1.2192)
			(layers "F.Cu" "F.Mask" "F.Paste")
			(net "P5E_PEX2_STN1_RX_DN<23>")
		)
		(pad "A45" smd rect
			(at 3.322574 15.655036 270)
			(size 0.3556 1.2192)
			(layers "F.Cu" "F.Mask" "F.Paste")
			(net "P5E_PEX2_STN1_RX_DP<23>")
		)
		(pad "A46" smd rect
			(at 3.322574 16.254984 270)
			(size 0.3556 1.2192)
			(layers "F.Cu" "F.Mask" "F.Paste")
			(net "GND")
		)
		(pad "A47" smd rect
			(at 3.322574 16.854932 270)
			(size 0.3556 1.2192)
			(layers "F.Cu" "F.Mask" "F.Paste")
			(net "P5E_PEX2_STN1_RX_DN<22>")
		)
		(pad "A48" smd rect
			(at 3.322574 17.45488 270)
			(size 0.3556 1.2192)
			(layers "F.Cu" "F.Mask" "F.Paste")
			(net "P5E_PEX2_STN1_RX_DP<22>")
		)
		(pad "A49" smd rect
			(at 3.322574 18.055082 270)
			(size 0.3556 1.2192)
			(layers "F.Cu" "F.Mask" "F.Paste")
			(net "GND")
		)
		(pad "A50" smd rect
			(at 3.322574 18.65503 270)
			(size 0.3556 1.2192)
			(layers "F.Cu" "F.Mask" "F.Paste")
			(net "P5E_PEX2_STN1_RX_DN<21>")
		)
		(pad "A51" smd rect
			(at 3.322574 19.254978 270)
			(size 0.3556 1.2192)
			(layers "F.Cu" "F.Mask" "F.Paste")
			(net "P5E_PEX2_STN1_RX_DP<21>")
		)
		(pad "A52" smd rect
			(at 3.322574 19.854926 270)
			(size 0.3556 1.2192)
			(layers "F.Cu" "F.Mask" "F.Paste")
			(net "GND")
		)
		(pad "A53" smd rect
			(at 3.322574 20.455128 270)
			(size 0.3556 1.2192)
			(layers "F.Cu" "F.Mask" "F.Paste")
			(net "P5E_PEX2_STN1_RX_DN<20>")
		)
		(pad "A54" smd rect
			(at 3.322574 21.055076 270)
			(size 0.3556 1.2192)
			(layers "F.Cu" "F.Mask" "F.Paste")
			(net "P5E_PEX2_STN1_RX_DP<20>")
		)
		(pad "A55" smd rect
			(at 3.322574 21.655024 270)
			(size 0.3556 1.2192)
			(layers "F.Cu" "F.Mask" "F.Paste")
			(net "GND")
		)
		(pad "A56" smd rect
			(at 3.322574 22.254972 270)
			(size 0.3556 1.2192)
			(layers "F.Cu" "F.Mask" "F.Paste")
			(net "P5E_PEX2_STN1_RX_DN<19>")
		)
		(pad "A57" smd rect
			(at 3.322574 22.85492 270)
			(size 0.3556 1.2192)
			(layers "F.Cu" "F.Mask" "F.Paste")
			(net "P5E_PEX2_STN1_RX_DP<19>")
		)
		(pad "A58" smd rect
			(at 3.322574 23.455122 270)
			(size 0.3556 1.2192)
			(layers "F.Cu" "F.Mask" "F.Paste")
			(net "GND")
		)
		(pad "A59" smd rect
			(at 3.322574 24.05507 270)
			(size 0.3556 1.2192)
			(layers "F.Cu" "F.Mask" "F.Paste")
			(net "P5E_PEX2_STN1_RX_DN<18>")
		)
		(pad "A60" smd rect
			(at 3.322574 24.655018 270)
			(size 0.3556 1.2192)
			(layers "F.Cu" "F.Mask" "F.Paste")
			(net "P5E_PEX2_STN1_RX_DP<18>")
		)
		(pad "A61" smd rect
			(at 3.322574 25.254966 270)
			(size 0.3556 1.2192)
			(layers "F.Cu" "F.Mask" "F.Paste")
			(net "GND")
		)
		(pad "A62" smd rect
			(at 3.322574 25.854914 270)
			(size 0.3556 1.2192)
			(layers "F.Cu" "F.Mask" "F.Paste")
			(net "P5E_PEX2_STN1_RX_DN<17>")
		)
		(pad "A63" smd rect
			(at 3.322574 26.455116 270)
			(size 0.3556 1.2192)
			(layers "F.Cu" "F.Mask" "F.Paste")
			(net "P5E_PEX2_STN1_RX_DP<17>")
		)
		(pad "A64" smd rect
			(at 3.322574 27.055064 270)
			(size 0.3556 1.2192)
			(layers "F.Cu" "F.Mask" "F.Paste")
			(net "GND")
		)
		(pad "A65" smd rect
			(at 3.322574 27.655012 270)
			(size 0.3556 1.2192)
			(layers "F.Cu" "F.Mask" "F.Paste")
			(net "P5E_PEX2_STN1_RX_DN<16>")
		)
		(pad "A66" smd rect
			(at 3.322574 28.25496 270)
			(size 0.3556 1.2192)
			(layers "F.Cu" "F.Mask" "F.Paste")
			(net "P5E_PEX2_STN1_RX_DP<16>")
		)
		(pad "A67" smd rect
			(at 3.322574 28.854908 270)
			(size 0.3556 1.2192)
			(layers "F.Cu" "F.Mask" "F.Paste")
			(net "GND")
		)
		(pad "A68" smd rect
			(at 3.322574 29.45511 270)
			(size 0.3556 1.2192)
			(layers "F.Cu" "F.Mask" "F.Paste")
			(net "Net_2635")
		)
		(pad "A69" smd rect
			(at 3.322574 30.055058 270)
			(size 0.3556 1.2192)
			(layers "F.Cu" "F.Mask" "F.Paste")
			(net "Net_2636")
		)
		(pad "A70" smd rect
			(at 3.322574 30.655006 270)
			(size 0.3556 1.2192)
			(layers "F.Cu" "F.Mask" "F.Paste")
			(net "NIC4_PWRBRK_R_N")
		)
		(pad "B1" smd rect
			(at -1.27762 -18.465038 270)
			(size 0.3556 1.2192)
			(layers "F.Cu" "F.Mask" "F.Paste")
			(net "P12V_NIC4")
		)
		(pad "B2" smd rect
			(at -1.27762 -17.86509 270)
			(size 0.3556 1.2192)
			(layers "F.Cu" "F.Mask" "F.Paste")
			(net "P12V_NIC4")
		)
		(pad "B3" smd rect
			(at -1.27762 -17.264888 270)
			(size 0.3556 1.2192)
			(layers "F.Cu" "F.Mask" "F.Paste")
			(net "P12V_NIC4")
		)
		(pad "B4" smd rect
			(at -1.27762 -16.66494 270)
			(size 0.3556 1.2192)
			(layers "F.Cu" "F.Mask" "F.Paste")
			(net "P12V_NIC4")
		)
		(pad "B5" smd rect
			(at -1.27762 -16.064992 270)
			(size 0.3556 1.2192)
			(layers "F.Cu" "F.Mask" "F.Paste")
			(net "P12V_NIC4")
		)
		(pad "B6" smd rect
			(at -1.27762 -15.465044 270)
			(size 0.3556 1.2192)
			(layers "F.Cu" "F.Mask" "F.Paste")
			(net "P12V_NIC4")
		)
		(pad "B7" smd rect
			(at -1.27762 -14.865096 270)
			(size 0.3556 1.2192)
			(layers "F.Cu" "F.Mask" "F.Paste")
			(net "NIC4_BIF0_N")
		)
		(pad "B8" smd rect
			(at -1.27762 -14.264894 270)
			(size 0.3556 1.2192)
			(layers "F.Cu" "F.Mask" "F.Paste")
			(net "NIC4_BIF1_N")
		)
		(pad "B9" smd rect
			(at -1.27762 -13.664946 270)
			(size 0.3556 1.2192)
			(layers "F.Cu" "F.Mask" "F.Paste")
			(net "NIC4_BIF2_N")
		)
		(pad "B10" smd rect
			(at -1.27762 -13.064998 270)
			(size 0.3556 1.2192)
			(layers "F.Cu" "F.Mask" "F.Paste")
			(net "RST_NIC4_PERST0_R_N")
		)
		(pad "B11" smd rect
			(at -1.27762 -12.46505 270)
			(size 0.3556 1.2192)
			(layers "F.Cu" "F.Mask" "F.Paste")
			(net "P3V3_NIC4")
		)
		(pad "B12" smd rect
			(at -1.27762 -11.865102 270)
			(size 0.3556 1.2192)
			(layers "F.Cu" "F.Mask" "F.Paste")
			(net "NIC4_AUX_PWR_EN_R")
		)
		(pad "B13" smd rect
			(at -1.27762 -11.2649 270)
			(size 0.3556 1.2192)
			(layers "F.Cu" "F.Mask" "F.Paste")
			(net "GND")
		)
		(pad "B14" smd rect
			(at -1.27762 -10.664952 270)
			(size 0.3556 1.2192)
			(layers "F.Cu" "F.Mask" "F.Paste")
			(net "CLK_100M_DB2000QL_NIC4_R_DN")
		)
		(pad "B15" smd rect
			(at -1.27762 -10.065004 270)
			(size 0.3556 1.2192)
			(layers "F.Cu" "F.Mask" "F.Paste")
			(net "CLK_100M_DB2000QL_NIC4_R_DP")
		)
		(pad "B16" smd rect
			(at -1.27762 -9.465056 270)
			(size 0.3556 1.2192)
			(layers "F.Cu" "F.Mask" "F.Paste")
			(net "GND")
		)
		(pad "B17" smd rect
			(at -1.27762 -8.865108 270)
			(size 0.3556 1.2192)
			(layers "F.Cu" "F.Mask" "F.Paste")
			(net "P5E_PEX2_STN1_TX_C_DP<31>")
		)
		(pad "B18" smd rect
			(at -1.27762 -8.264906 270)
			(size 0.3556 1.2192)
			(layers "F.Cu" "F.Mask" "F.Paste")
			(net "P5E_PEX2_STN1_TX_C_DN<31>")
		)
		(pad "B19" smd rect
			(at -1.27762 -7.664958 270)
			(size 0.3556 1.2192)
			(layers "F.Cu" "F.Mask" "F.Paste")
			(net "GND")
		)
		(pad "B20" smd rect
			(at -1.27762 -7.06501 270)
			(size 0.3556 1.2192)
			(layers "F.Cu" "F.Mask" "F.Paste")
			(net "P5E_PEX2_STN1_TX_C_DN<30>")
		)
		(pad "B21" smd rect
			(at -1.27762 -6.465062 270)
			(size 0.3556 1.2192)
			(layers "F.Cu" "F.Mask" "F.Paste")
			(net "P5E_PEX2_STN1_TX_C_DP<30>")
		)
		(pad "B22" smd rect
			(at -1.27762 -5.865114 270)
			(size 0.3556 1.2192)
			(layers "F.Cu" "F.Mask" "F.Paste")
			(net "GND")
		)
		(pad "B23" smd rect
			(at -1.27762 -5.264912 270)
			(size 0.3556 1.2192)
			(layers "F.Cu" "F.Mask" "F.Paste")
			(net "P5E_PEX2_STN1_TX_C_DP<29>")
		)
		(pad "B24" smd rect
			(at -1.27762 -4.664964 270)
			(size 0.3556 1.2192)
			(layers "F.Cu" "F.Mask" "F.Paste")
			(net "P5E_PEX2_STN1_TX_C_DN<29>")
		)
		(pad "B25" smd rect
			(at -1.27762 -4.065016 270)
			(size 0.3556 1.2192)
			(layers "F.Cu" "F.Mask" "F.Paste")
			(net "GND")
		)
		(pad "B26" smd rect
			(at -1.27762 -3.465068 270)
			(size 0.3556 1.2192)
			(layers "F.Cu" "F.Mask" "F.Paste")
			(net "P5E_PEX2_STN1_TX_C_DN<28>")
		)
		(pad "B27" smd rect
			(at -1.27762 -2.86512 270)
			(size 0.3556 1.2192)
			(layers "F.Cu" "F.Mask" "F.Paste")
			(net "P5E_PEX2_STN1_TX_C_DP<28>")
		)
		(pad "B28" smd rect
			(at -1.27762 -2.264918 270)
			(size 0.3556 1.2192)
			(layers "F.Cu" "F.Mask" "F.Paste")
			(net "GND")
		)
		(pad "B29" smd rect
			(at -1.27762 1.74498 270)
			(size 0.3556 1.2192)
			(layers "F.Cu" "F.Mask" "F.Paste")
			(net "GND")
		)
		(pad "B30" smd rect
			(at -1.27762 2.344928 270)
			(size 0.3556 1.2192)
			(layers "F.Cu" "F.Mask" "F.Paste")
			(net "P5E_PEX2_STN1_TX_C_DP<27>")
		)
		(pad "B31" smd rect
			(at -1.27762 2.944876 270)
			(size 0.3556 1.2192)
			(layers "F.Cu" "F.Mask" "F.Paste")
			(net "P5E_PEX2_STN1_TX_C_DN<27>")
		)
		(pad "B32" smd rect
			(at -1.27762 3.545078 270)
			(size 0.3556 1.2192)
			(layers "F.Cu" "F.Mask" "F.Paste")
			(net "GND")
		)
		(pad "B33" smd rect
			(at -1.27762 4.145026 270)
			(size 0.3556 1.2192)
			(layers "F.Cu" "F.Mask" "F.Paste")
			(net "P5E_PEX2_STN1_TX_C_DN<26>")
		)
		(pad "B34" smd rect
			(at -1.27762 4.744974 270)
			(size 0.3556 1.2192)
			(layers "F.Cu" "F.Mask" "F.Paste")
			(net "P5E_PEX2_STN1_TX_C_DP<26>")
		)
		(pad "B35" smd rect
			(at -1.27762 5.344922 270)
			(size 0.3556 1.2192)
			(layers "F.Cu" "F.Mask" "F.Paste")
			(net "GND")
		)
		(pad "B36" smd rect
			(at -1.27762 5.945124 270)
			(size 0.3556 1.2192)
			(layers "F.Cu" "F.Mask" "F.Paste")
			(net "P5E_PEX2_STN1_TX_C_DP<25>")
		)
		(pad "B37" smd rect
			(at -1.27762 6.545072 270)
			(size 0.3556 1.2192)
			(layers "F.Cu" "F.Mask" "F.Paste")
			(net "P5E_PEX2_STN1_TX_C_DN<25>")
		)
	)
)
